(kicad_pcb
	(version 20260206)
	(generator "pcbnew")
	(generator_version "10.0")
	(general
		(thickness 1.6)
		(legacy_teardrops no)
	)
	(paper "A4")
	(title_block
		(title "Bryce Canyon_IOM_M2_16342-2_OCP.brd")
		(comment 1 "Bryce Canyon / footprints 139-146 of 1146")
	)
	(layers
		(0 "F.Cu" signal "TOP")
		(4 "In1.Cu" signal "L2GND")
		(6 "In2.Cu" signal "L3")
		(8 "In3.Cu" signal "L4VCC")
		(10 "In4.Cu" signal "L5VCC")
		(12 "In5.Cu" signal "L6")
		(14 "In6.Cu" signal "L7GND")
		(2 "B.Cu" signal "BOTTOM")
		(9 "F.Adhes" user "F.Adhesive")
		(11 "B.Adhes" user "B.Adhesive")
		(13 "F.Paste" user "Package Geometry/Pastemask Top")
		(15 "B.Paste" user "Package Geometry/Pastemask Bottom")
		(5 "F.SilkS" user "Ref Des/Silkscreen Top")
		(7 "B.SilkS" user "Ref Des/Silkscreen Bottom")
		(1 "F.Mask" user "Board Geometry/Soldermask Top")
		(3 "B.Mask" user "Board Geometry/Soldermask Bottom")
		(17 "Dwgs.User" user "User.Drawings")
		(19 "Cmts.User" user "User.Comments")
		(21 "Eco1.User" user "User.Eco1")
		(23 "Eco2.User" user "User.Eco2")
		(25 "Edge.Cuts" user "Board Geometry/Outline")
		(27 "Margin" user)
		(31 "F.CrtYd" user "Package Geometry/Place Bound Top")
		(29 "B.CrtYd" user "Package Geometry/Place Bound Bottom")
		(35 "F.Fab" user "Ref Des/Assembly Top")
		(33 "B.Fab" user "Ref Des/Assembly Bottom")
	)
	(footprint ""
		(layer "F.Cu")
		(at 12.499848 -187.999878)
		(property "Reference" ""
			(at 0 0 0)
			(layer "F.SilkS")
			(hide yes)
			(effects
				(font
					(size 1.27 1.27)
				)
			)
		)
		(property "Value" "*"
			(at 6.2484 0.3429 0)
			(unlocked yes)
			(layer "F.Fab")
			(hide yes)
			(effects
				(font
					(size 1.016 1.016)
					(thickness 0.1524)
				)
			)
		)
		(duplicate_pad_numbers_are_jumpers no)
		(fp_poly
			(pts
				(arc
					(start 5.0673 0)
					(mid -5.0673 0)
					(end 5.0673 0)
				)
			)
			(stroke
				(width 0)
				(type default)
			)
			(fill no)
			(layer "B.CrtYd")
		)
		(fp_poly
			(pts
				(arc
					(start 5.0673 0)
					(mid -5.0673 0)
					(end 5.0673 0)
				)
			)
			(stroke
				(width 0)
				(type default)
			)
			(fill no)
			(layer "F.CrtYd")
		)
		(fp_poly
			(pts
				(arc
					(start 5.0673 0)
					(mid -5.0673 0)
					(end 5.0673 0)
				)
			)
			(stroke
				(width 0)
				(type default)
			)
			(fill no)
			(layer "B.Fab")
		)
		(fp_poly
			(pts
				(arc
					(start 5.0673 0)
					(mid -5.0673 0)
					(end 5.0673 0)
				)
			)
			(stroke
				(width 0)
				(type default)
			)
			(fill no)
			(layer "F.Fab")
		)
		(pad "1" thru_hole circle
			(at 0 0)
			(size 9.525 9.525)
			(drill 4.0132)
			(layers "*.Cu" "*.Mask")
			(remove_unused_layers no)
			(net "Net_85")
			(clearance -2.2479)
			(thermal_gap 0.3048)
			(padstack
				(mode front_inner_back)
				(layer "Inner"
					(shape circle)
					(size 4.4196 4.4196)
					(clearance 0.3048)
				)
				(layer "B.Cu"
					(shape circle)
					(size 9.525 9.525)
					(clearance -2.2479)
				)
			)
		)
	)
	(footprint ""
		(layer "F.Cu")
		(at 47.540418 -128.189736)
		(property "Reference" "R200"
			(at 0 0 0)
			(layer "F.SilkS")
			(hide yes)
			(effects
				(font
					(size 1.27 1.27)
				)
			)
		)
		(property "Value" "2K2R2F-GP"
			(at 0.064008 -3.993896 0)
			(unlocked yes)
			(layer "F.Fab")
			(hide yes)
			(effects
				(font
					(size 1.016 1.016)
					(thickness 0.1524)
				)
			)
		)
		(property "Device Type" "R402H16"
			(at 0.064008 -5.517896 0)
			(unlocked yes)
			(layer "F.Fab")
			(hide yes)
			(effects
				(font
					(size 1.016 1.016)
					(thickness 0.1524)
				)
			)
		)
		(duplicate_pad_numbers_are_jumpers no)
		(fp_line
			(start -0.508 -0.9398)
			(end -0.508 0.9398)
			(stroke
				(width 0.1524)
				(type default)
			)
			(layer "F.SilkS")
		)
		(fp_line
			(start 0.508 -0.9398)
			(end -0.508 -0.9398)
			(stroke
				(width 0.1524)
				(type default)
			)
			(layer "F.SilkS")
		)
		(fp_rect
			(start -0.508 0.9398)
			(end 0.508 -0.9398)
			(stroke
				(width 0)
				(type default)
			)
			(fill no)
			(layer "F.CrtYd")
		)
		(fp_rect
			(start -0.508 0.9398)
			(end 0.508 -0.9398)
			(stroke
				(width 0)
				(type default)
			)
			(fill no)
			(layer "F.Fab")
		)
		(pad "1" smd custom
			(at 0 -0.4445)
			(size 0.1397 0.1397)
			(layers "F.Cu" "F.Mask" "F.Paste")
			(net "I2C_TPM_SCL")
			(options
				(clearance outline)
				(anchor circle)
			)
			(primitives
				(gr_poly
					(pts
						(arc
							(start -0.1778 -0.2794)
							(mid -0.249642 -0.249642)
							(end -0.2794 -0.1778)
						)
						(arc
							(start -0.2794 0.1778)
							(mid -0.249642 0.249642)
							(end -0.1778 0.2794)
						)
						(arc
							(start 0.1778 0.2794)
							(mid 0.249642 0.249642)
							(end 0.2794 0.1778)
						)
						(arc
							(start 0.2794 -0.1778)
							(mid 0.249642 -0.249642)
							(end 0.1778 -0.2794)
						)
					)
					(width 0)
					(fill yes)
				)
			)
		)
		(pad "2" smd custom
			(at 0 0.4445)
			(size 0.1397 0.1397)
			(layers "F.Cu" "F.Mask" "F.Paste")
			(net "P3V3_STBY")
			(options
				(clearance outline)
				(anchor circle)
			)
			(primitives
				(gr_poly
					(pts
						(arc
							(start -0.1778 -0.2794)
							(mid -0.249642 -0.249642)
							(end -0.2794 -0.1778)
						)
						(arc
							(start -0.2794 0.1778)
							(mid -0.249642 0.249642)
							(end -0.1778 0.2794)
						)
						(arc
							(start 0.1778 0.2794)
							(mid 0.249642 0.249642)
							(end 0.2794 0.1778)
						)
						(arc
							(start 0.2794 -0.1778)
							(mid 0.249642 -0.249642)
							(end 0.1778 -0.2794)
						)
					)
					(width 0)
					(fill yes)
				)
			)
		)
	)
	(footprint ""
		(layer "F.Cu")
		(at 180.319426 -140.483082 -135)
		(property "Reference" "VIA60"
			(at 0 0 225)
			(layer "F.SilkS")
			(hide yes)
			(effects
				(font
					(size 1.27 1.27)
				)
			)
		)
		(property "Value" "85OHM-8L-1D6MM-L16L18-GP"
			(at 4.064105 0.609655 225)
			(unlocked yes)
			(layer "F.Fab")
			(hide yes)
			(effects
				(font
					(size 1.016 1.016)
					(thickness 0.1524)
				)
			)
		)
		(property "Device Type" "VIA-PCIE-4P-368076"
			(at 4.064105 -0.914474 225)
			(unlocked yes)
			(layer "F.Fab")
			(hide yes)
			(effects
				(font
					(size 1.016 1.016)
					(thickness 0.1524)
				)
			)
		)
		(duplicate_pad_numbers_are_jumpers no)
		(fp_poly
			(pts
				(xy -1.841491 -0.381057) (xy 1.841509 -0.381058) (xy 1.841508 0.380942) (xy -1.841491 0.380942)
			)
			(stroke
				(width 0)
				(type default)
			)
			(fill no)
			(layer "F.CrtYd")
		)
		(fp_poly
			(pts
				(xy -1.841491 -0.381057) (xy 1.841509 -0.381058) (xy 1.841508 0.380942) (xy -1.841491 0.380942)
			)
			(stroke
				(width 0)
				(type default)
			)
			(fill no)
			(layer "F.Fab")
		)
		(pad "1" thru_hole circle
			(at -1.460499 0 225)
			(size 0.508 0.508)
			(drill 0.254)
			(layers "*.Cu" "*.Mask")
			(remove_unused_layers no)
			(net "GND")
			(clearance 0.127)
			(thermal_gap 0.127)
		)
		(pad "2" thru_hole circle
			(at -0.4445 0 225)
			(size 0.508 0.508)
			(drill 0.254)
			(layers "*.Cu" "*.Mask")
			(remove_unused_layers no)
			(net "PCIE_COMP_TO_IOM_13_DP")
			(clearance 0.127)
			(thermal_gap 0.127)
		)
		(pad "3" thru_hole circle
			(at 0.4445 0 225)
			(size 0.508 0.508)
			(drill 0.254)
			(layers "*.Cu" "*.Mask")
			(remove_unused_layers no)
			(net "PCIE_COMP_TO_IOM_13_DN")
			(clearance 0.127)
			(thermal_gap 0.127)
		)
		(pad "4" thru_hole circle
			(at 1.460499 0 225)
			(size 0.508 0.508)
			(drill 0.254)
			(layers "*.Cu" "*.Mask")
			(remove_unused_layers no)
			(net "GND")
			(clearance 0.127)
			(thermal_gap 0.127)
		)
	)
	(footprint ""
		(layer "F.Cu")
		(at 152.488138 -19.559778 -90)
		(property "Reference" "R512"
			(at 0 0 270)
			(layer "F.SilkS")
			(hide yes)
			(effects
				(font
					(size 1.27 1.27)
				)
			)
		)
		(property "Value" "0R6J-3-GP"
			(at -0.0508 -4.8514 270)
			(unlocked yes)
			(layer "F.Fab")
			(hide yes)
			(effects
				(font
					(size 1.016 1.016)
					(thickness 0.1524)
				)
			)
		)
		(property "Device Type" "R1206H28"
			(at 0 -6.3754 270)
			(unlocked yes)
			(layer "F.Fab")
			(hide yes)
			(effects
				(font
					(size 1.016 1.016)
					(thickness 0.1524)
				)
			)
		)
		(duplicate_pad_numbers_are_jumpers no)
		(fp_line
			(start -1.016 2.2352)
			(end -1.016 -2.2352)
			(stroke
				(width 0.1524)
				(type default)
			)
			(layer "F.SilkS")
		)
		(fp_line
			(start 1.016 2.2352)
			(end -1.016 2.2352)
			(stroke
				(width 0.1524)
				(type default)
			)
			(layer "F.SilkS")
		)
		(fp_line
			(start -1.016 -2.2352)
			(end 1.016 -2.2352)
			(stroke
				(width 0.1524)
				(type default)
			)
			(layer "F.SilkS")
		)
		(fp_line
			(start 1.016 -2.2352)
			(end 1.016 2.2352)
			(stroke
				(width 0.1524)
				(type default)
			)
			(layer "F.SilkS")
		)
		(fp_rect
			(start -1.0922 2.3114)
			(end 1.0922 -2.3114)
			(stroke
				(width 0)
				(type default)
			)
			(fill no)
			(layer "F.CrtYd")
		)
		(fp_poly
			(pts
				(xy -1.0922 -2.3114) (xy 1.0922 -2.3114) (xy 1.0922 2.3114) (xy -1.0922 2.3114)
			)
			(stroke
				(width 0)
				(type default)
			)
			(fill no)
			(layer "F.Fab")
		)
		(pad "1" smd rect
			(at 0 -1.397 270)
			(size 1.651 1.27)
			(layers "F.Cu" "F.Mask" "F.Paste")
			(net "P12V_STBY_VIN_PU4")
		)
		(pad "2" smd rect
			(at 0 1.397 270)
			(size 1.651 1.27)
			(layers "F.Cu" "F.Mask" "F.Paste")
			(net "P12V_STBY")
		)
	)
	(footprint ""
		(layer "F.Cu")
		(at 33.772348 -153.240994 -90)
		(property "Reference" "R319"
			(at 0 0 270)
			(layer "F.SilkS")
			(hide yes)
			(effects
				(font
					(size 1.27 1.27)
				)
			)
		)
		(property "Value" "0R2J-2-GP"
			(at 0.064008 -3.993896 270)
			(unlocked yes)
			(layer "F.Fab")
			(hide yes)
			(effects
				(font
					(size 1.016 1.016)
					(thickness 0.1524)
				)
			)
		)
		(property "Device Type" "R402H16"
			(at 0.064008 -5.517896 270)
			(unlocked yes)
			(layer "F.Fab")
			(hide yes)
			(effects
				(font
					(size 1.016 1.016)
					(thickness 0.1524)
				)
			)
		)
		(duplicate_pad_numbers_are_jumpers no)
		(fp_line
			(start -0.508 -0.9398)
			(end -0.508 0.9398)
			(stroke
				(width 0.1524)
				(type default)
			)
			(layer "F.SilkS")
		)
		(fp_line
			(start 0.508 -0.9398)
			(end -0.508 -0.9398)
			(stroke
				(width 0.1524)
				(type default)
			)
			(layer "F.SilkS")
		)
		(fp_rect
			(start -0.508 0.9398)
			(end 0.508 -0.9398)
			(stroke
				(width 0)
				(type default)
			)
			(fill no)
			(layer "F.CrtYd")
		)
		(fp_rect
			(start -0.508 0.9398)
			(end 0.508 -0.9398)
			(stroke
				(width 0)
				(type default)
			)
			(fill no)
			(layer "F.Fab")
		)
		(pad "1" smd custom
			(at 0 -0.4445 270)
			(size 0.1397 0.1397)
			(layers "F.Cu" "F.Mask" "F.Paste")
			(net "ENCL_FAULT_LED_R")
			(options
				(clearance outline)
				(anchor circle)
			)
			(primitives
				(gr_poly
					(pts
						(arc
							(start -0.1778 -0.2794)
							(mid -0.249642 -0.249642)
							(end -0.2794 -0.1778)
						)
						(arc
							(start -0.2794 0.1778)
							(mid -0.249642 0.249642)
							(end -0.1778 0.2794)
						)
						(arc
							(start 0.1778 0.2794)
							(mid 0.249642 0.249642)
							(end 0.2794 0.1778)
						)
						(arc
							(start 0.2794 -0.1778)
							(mid 0.249642 -0.249642)
							(end 0.1778 -0.2794)
						)
					)
					(width 0)
					(fill yes)
				)
			)
		)
		(pad "2" smd custom
			(at 0 0.4445 270)
			(size 0.1397 0.1397)
			(layers "F.Cu" "F.Mask" "F.Paste")
			(net "ENCL_FAULT_LED")
			(options
				(clearance outline)
				(anchor circle)
			)
			(primitives
				(gr_poly
					(pts
						(arc
							(start -0.1778 -0.2794)
							(mid -0.249642 -0.249642)
							(end -0.2794 -0.1778)
						)
						(arc
							(start -0.2794 0.1778)
							(mid -0.249642 0.249642)
							(end -0.1778 0.2794)
						)
						(arc
							(start 0.1778 0.2794)
							(mid 0.249642 0.249642)
							(end 0.2794 0.1778)
						)
						(arc
							(start 0.2794 -0.1778)
							(mid 0.249642 -0.249642)
							(end 0.1778 -0.2794)
						)
					)
					(width 0)
					(fill yes)
				)
			)
		)
	)
	(footprint ""
		(layer "F.Cu")
		(at 214.903558 -39.096696)
		(property "Reference" "R713"
			(at 0 0 0)
			(layer "F.SilkS")
			(hide yes)
			(effects
				(font
					(size 1.27 1.27)
				)
			)
		)
		(property "Value" "0R2J-2-GP"
			(at 0.064008 -3.993896 0)
			(unlocked yes)
			(layer "F.Fab")
			(hide yes)
			(effects
				(font
					(size 1.016 1.016)
					(thickness 0.1524)
				)
			)
		)
		(property "Device Type" "R402H16"
			(at 0.064008 -5.517896 0)
			(unlocked yes)
			(layer "F.Fab")
			(hide yes)
			(effects
				(font
					(size 1.016 1.016)
					(thickness 0.1524)
				)
			)
		)
		(duplicate_pad_numbers_are_jumpers no)
		(fp_line
			(start -0.508 -0.9398)
			(end -0.508 0.9398)
			(stroke
				(width 0.1524)
				(type default)
			)
			(layer "F.SilkS")
		)
		(fp_line
			(start 0.508 -0.9398)
			(end -0.508 -0.9398)
			(stroke
				(width 0.1524)
				(type default)
			)
			(layer "F.SilkS")
		)
		(fp_rect
			(start -0.508 0.9398)
			(end 0.508 -0.9398)
			(stroke
				(width 0)
				(type default)
			)
			(fill no)
			(layer "F.CrtYd")
		)
		(fp_rect
			(start -0.508 0.9398)
			(end 0.508 -0.9398)
			(stroke
				(width 0)
				(type default)
			)
			(fill no)
			(layer "F.Fab")
		)
		(pad "1" smd custom
			(at 0 -0.4445)
			(size 0.1397 0.1397)
			(layers "F.Cu" "F.Mask" "F.Paste")
			(net "P5V_EN_R")
			(options
				(clearance outline)
				(anchor circle)
			)
			(primitives
				(gr_poly
					(pts
						(arc
							(start -0.1778 -0.2794)
							(mid -0.249642 -0.249642)
							(end -0.2794 -0.1778)
						)
						(arc
							(start -0.2794 0.1778)
							(mid -0.249642 0.249642)
							(end -0.1778 0.2794)
						)
						(arc
							(start 0.1778 0.2794)
							(mid 0.249642 0.249642)
							(end 0.2794 0.1778)
						)
						(arc
							(start 0.2794 -0.1778)
							(mid 0.249642 -0.249642)
							(end 0.1778 -0.2794)
						)
					)
					(width 0)
					(fill yes)
				)
			)
		)
		(pad "2" smd custom
			(at 0 0.4445)
			(size 0.1397 0.1397)
			(layers "F.Cu" "F.Mask" "F.Paste")
			(net "P12V_IOM_PGOOD")
			(options
				(clearance outline)
				(anchor circle)
			)
			(primitives
				(gr_poly
					(pts
						(arc
							(start -0.1778 -0.2794)
							(mid -0.249642 -0.249642)
							(end -0.2794 -0.1778)
						)
						(arc
							(start -0.2794 0.1778)
							(mid -0.249642 0.249642)
							(end -0.1778 0.2794)
						)
						(arc
							(start 0.1778 0.2794)
							(mid 0.249642 0.249642)
							(end 0.2794 0.1778)
						)
						(arc
							(start 0.2794 -0.1778)
							(mid 0.249642 -0.249642)
							(end 0.1778 -0.2794)
						)
					)
					(width 0)
					(fill yes)
				)
			)
		)
	)
	(footprint ""
		(layer "F.Cu")
		(at 98.298 -171.6024 -90)
		(property "Reference" "R724"
			(at 0 0 270)
			(layer "F.SilkS")
			(hide yes)
			(effects
				(font
					(size 1.27 1.27)
				)
			)
		)
		(property "Value" "0R2J-2-GP"
			(at 0.064008 -3.993896 270)
			(unlocked yes)
			(layer "F.Fab")
			(hide yes)
			(effects
				(font
					(size 1.016 1.016)
					(thickness 0.1524)
				)
			)
		)
		(property "Device Type" "R402H16"
			(at 0.064008 -5.517896 270)
			(unlocked yes)
			(layer "F.Fab")
			(hide yes)
			(effects
				(font
					(size 1.016 1.016)
					(thickness 0.1524)
				)
			)
		)
		(duplicate_pad_numbers_are_jumpers no)
		(fp_line
			(start -0.508 -0.9398)
			(end -0.508 0.9398)
			(stroke
				(width 0.1524)
				(type default)
			)
			(layer "F.SilkS")
		)
		(fp_line
			(start 0.508 -0.9398)
			(end -0.508 -0.9398)
			(stroke
				(width 0.1524)
				(type default)
			)
			(layer "F.SilkS")
		)
		(fp_rect
			(start -0.508 0.9398)
			(end 0.508 -0.9398)
			(stroke
				(width 0)
				(type default)
			)
			(fill no)
			(layer "F.CrtYd")
		)
		(fp_rect
			(start -0.508 0.9398)
			(end 0.508 -0.9398)
			(stroke
				(width 0)
				(type default)
			)
			(fill no)
			(layer "F.Fab")
		)
		(pad "1" smd custom
			(at 0 -0.4445 270)
			(size 0.1397 0.1397)
			(layers "F.Cu" "F.Mask" "F.Paste")
			(net "DPB_MISC_ALERT_OUT")
			(options
				(clearance outline)
				(anchor circle)
			)
			(primitives
				(gr_poly
					(pts
						(arc
							(start -0.1778 -0.2794)
							(mid -0.249642 -0.249642)
							(end -0.2794 -0.1778)
						)
						(arc
							(start -0.2794 0.1778)
							(mid -0.249642 0.249642)
							(end -0.1778 0.2794)
						)
						(arc
							(start 0.1778 0.2794)
							(mid 0.249642 0.249642)
							(end 0.2794 0.1778)
						)
						(arc
							(start 0.2794 -0.1778)
							(mid 0.249642 -0.249642)
							(end 0.1778 -0.2794)
						)
					)
					(width 0)
					(fill yes)
				)
			)
		)
		(pad "2" smd custom
			(at 0 0.4445 270)
			(size 0.1397 0.1397)
			(layers "F.Cu" "F.Mask" "F.Paste")
			(net "DPB_MISC_ALERT_OUT_R")
			(options
				(clearance outline)
				(anchor circle)
			)
			(primitives
				(gr_poly
					(pts
						(arc
							(start -0.1778 -0.2794)
							(mid -0.249642 -0.249642)
							(end -0.2794 -0.1778)
						)
						(arc
							(start -0.2794 0.1778)
							(mid -0.249642 0.249642)
							(end -0.1778 0.2794)
						)
						(arc
							(start 0.1778 0.2794)
							(mid 0.249642 0.249642)
							(end 0.2794 0.1778)
						)
						(arc
							(start 0.2794 -0.1778)
							(mid 0.249642 -0.249642)
							(end 0.1778 -0.2794)
						)
					)
					(width 0)
					(fill yes)
				)
			)
		)
	)
	(footprint ""
		(layer "F.Cu")
		(at 44.345352 -124.818902)
		(property "Reference" "R89"
			(at 0 0 0)
			(layer "F.SilkS")
			(hide yes)
			(effects
				(font
					(size 1.27 1.27)
				)
			)
		)
		(property "Value" "33D2R2F-GP"
			(at 0.064008 -3.993896 0)
			(unlocked yes)
			(layer "F.Fab")
			(hide yes)
			(effects
				(font
					(size 1.016 1.016)
					(thickness 0.1524)
				)
			)
		)
		(property "Device Type" "R402H16"
			(at 0.064008 -5.517896 0)
			(unlocked yes)
			(layer "F.Fab")
			(hide yes)
			(effects
				(font
					(size 1.016 1.016)
					(thickness 0.1524)
				)
			)
		)
		(duplicate_pad_numbers_are_jumpers no)
		(fp_line
			(start -0.508 -0.9398)
			(end -0.508 0.9398)
			(stroke
				(width 0.1524)
				(type default)
			)
			(layer "F.SilkS")
		)
		(fp_line
			(start 0.508 -0.9398)
			(end -0.508 -0.9398)
			(stroke
				(width 0.1524)
				(type default)
			)
			(layer "F.SilkS")
		)
		(fp_rect
			(start -0.508 0.9398)
			(end 0.508 -0.9398)
			(stroke
				(width 0)
				(type default)
			)
			(fill no)
			(layer "F.CrtYd")
		)
		(fp_rect
			(start -0.508 0.9398)
			(end 0.508 -0.9398)
			(stroke
				(width 0)
				(type default)
			)
			(fill no)
			(layer "F.Fab")
		)
		(pad "1" smd custom
			(at 0 -0.4445)
			(size 0.1397 0.1397)
			(layers "F.Cu" "F.Mask" "F.Paste")
			(net "BMC_SPI_MISO")
			(options
				(clearance outline)
				(anchor circle)
			)
			(primitives
				(gr_poly
					(pts
						(arc
							(start -0.1778 -0.2794)
							(mid -0.249642 -0.249642)
							(end -0.2794 -0.1778)
						)
						(arc
							(start -0.2794 0.1778)
							(mid -0.249642 0.249642)
							(end -0.1778 0.2794)
						)
						(arc
							(start 0.1778 0.2794)
							(mid 0.249642 0.249642)
							(end 0.2794 0.1778)
						)
						(arc
							(start 0.2794 -0.1778)
							(mid 0.249642 -0.249642)
							(end 0.1778 -0.2794)
						)
					)
					(width 0)
					(fill yes)
				)
			)
		)
		(pad "2" smd custom
			(at 0 0.4445)
			(size 0.1397 0.1397)
			(layers "F.Cu" "F.Mask" "F.Paste")
			(net "BMC_SPI_MISO_TPM")
			(options
				(clearance outline)
				(anchor circle)
			)
			(primitives
				(gr_poly
					(pts
						(arc
							(start -0.1778 -0.2794)
							(mid -0.249642 -0.249642)
							(end -0.2794 -0.1778)
						)
						(arc
							(start -0.2794 0.1778)
							(mid -0.249642 0.249642)
							(end -0.1778 0.2794)
						)
						(arc
							(start 0.1778 0.2794)
							(mid 0.249642 0.249642)
							(end 0.2794 0.1778)
						)
						(arc
							(start 0.2794 -0.1778)
							(mid 0.249642 -0.249642)
							(end 0.1778 -0.2794)
						)
					)
					(width 0)
					(fill yes)
				)
			)
		)
	)
)
